FILE_TYPE = CONNECTIVITY;
{Allegro Design Entry HDL 17.4-2019 S026 (4007227) 1/17/2022}
"PAGE_NUMBER" = 51;
0"NC";
1"P5E_CPU1_P1_TX_DN<15:0>";
2"P5E_CPU1_P1_TX_DP<15:0>";
3"P5E_CPU1_P0_RX_DN<15:0>";
4"P5E_CPU1_P1_RX_DP<15:0>";
5"P5E_CPU1_P0_RX_DP<15:0>";
6"P5E_CPU1_P0_TX_DN<15:0>";
7"P5E_CPU1_P0_TX_DP<15:0>";
8"P5E_CPU1_P1_RX_DN<15:0>";
9"P5E_CPU1_P1_RX_DN<2>";
10"P5E_CPU1_P1_TX_DP<0>";
11"P5E_CPU1_P1_RX_DN<0>";
12"P5E_CPU1_P1_RX_DN<13>";
13"P5E_CPU1_P1_RX_DN<12>";
14"P5E_CPU1_P1_RX_DN<11>";
15"P5E_CPU1_P1_RX_DN<10>";
16"P5E_CPU1_P1_RX_DN<9>";
17"P5E_CPU1_P1_RX_DN<8>";
18"P5E_CPU1_P1_RX_DN<7>";
19"P5E_CPU1_P1_RX_DN<6>";
20"P5E_CPU1_P1_RX_DN<5>";
21"P5E_CPU1_P1_RX_DN<4>";
22"P5E_CPU1_P1_RX_DN<3>";
23"P5E_CPU1_P1_RX_DN<1>";
24"P5E_CPU1_P1_RX_DN<14>";
25"P5E_CPU1_P1_RX_DN<15>";
26"P5E_CPU1_P1_RX_DP<15>";
27"P5E_CPU1_P1_RX_DP<14>";
28"P5E_CPU1_P1_RX_DP<11>";
29"P5E_CPU1_P1_RX_DP<9>";
30"P5E_CPU1_P1_RX_DP<8>";
31"P5E_CPU1_P1_RX_DP<7>";
32"P5E_CPU1_P1_RX_DP<6>";
33"P5E_CPU1_P1_RX_DP<5>";
34"P5E_CPU1_P1_RX_DP<4>";
35"P5E_CPU1_P1_RX_DP<3>";
36"P5E_CPU1_P1_RX_DP<2>";
37"P5E_CPU1_P1_RX_DP<0>";
38"P5E_CPU1_P1_RX_DP<1>";
39"P5E_CPU1_P1_TX_DN<1>";
40"P5E_CPU1_P0_TX_DN<9>";
41"P5E_CPU1_P0_TX_DP<9>";
42"P5E_CPU1_P0_TX_DN<8>";
43"P5E_CPU1_P0_RX_DN<7>";
44"P5E_CPU1_P0_RX_DN<1>";
45"P5E_CPU1_P0_RX_DN<0>";
46"P5E_CPU1_P0_TX_DP<15>";
47"P5E_CPU1_P0_RX_DP<0>";
48"P5E_CPU1_P0_RX_DP<10>";
49"P5E_CPU1_P0_RX_DP<15>";
50"P5E_CPU1_P0_RX_DP<14>";
51"P5E_CPU1_P0_RX_DP<13>";
52"P5E_CPU1_P0_RX_DN<11>";
53"P5E_CPU1_P0_RX_DN<12>";
54"P5E_CPU1_P0_RX_DN<10>";
55"P5E_CPU1_P0_RX_DN<9>";
56"P5E_CPU1_P0_RX_DP<9>";
57"P5E_CPU1_P0_RX_DN<8>";
58"P5E_CPU1_P0_RX_DN<6>";
59"P5E_CPU1_P0_RX_DP<7>";
60"P5E_CPU1_P0_RX_DP<8>";
61"P5E_CPU1_P0_TX_DN<13>";
62"P5E_CPU1_P0_TX_DN<12>";
63"P5E_CPU1_P0_TX_DN<11>";
64"P5E_CPU1_P0_TX_DP<14>";
65"P5E_CPU1_P0_TX_DP<13>";
66"P5E_CPU1_P0_TX_DP<12>";
67"P5E_CPU1_P0_TX_DP<8>";
68"P5E_CPU1_P0_TX_DN<7>";
69"P5E_CPU1_P0_RX_DN<5>";
70"P5E_CPU1_P0_RX_DP<6>";
71"P5E_CPU1_P0_RX_DN<4>";
72"P5E_CPU1_P0_TX_DP<11>";
73"P5E_CPU1_P0_TX_DN<10>";
74"P5E_CPU1_P0_TX_DP<7>";
75"P5E_CPU1_P0_TX_DN<6>";
76"P5E_CPU1_P0_TX_DN<4>";
77"P5E_CPU1_P0_TX_DP<4>";
78"P5E_CPU1_P0_TX_DN<3>";
79"P5E_CPU1_P0_TX_DP<3>";
80"P5E_CPU1_P0_TX_DN<2>";
81"P5E_CPU1_P0_TX_DP<2>";
82"P5E_CPU1_P0_TX_DN<1>";
83"P5E_CPU1_P0_TX_DP<1>";
84"P5E_CPU1_P0_TX_DN<15>";
85"P5E_CPU1_P0_TX_DN<14>";
86"P5E_CPU1_P0_TX_DN<0>";
87"P5E_CPU1_P0_TX_DP<0>";
88"P5E_CPU1_P0_RX_DP<1>";
89"P5E_CPU1_P0_RX_DP<2>";
90"P5E_CPU1_P0_RX_DN<2>";
91"P5E_CPU1_P0_RX_DP<3>";
92"P5E_CPU1_P0_RX_DN<3>";
93"P5E_CPU1_P0_RX_DP<4>";
94"P5E_CPU1_P0_TX_DP<5>";
95"P5E_CPU1_P0_TX_DP<10>";
96"P5E_CPU1_P0_TX_DP<6>";
97"P5E_CPU1_P0_TX_DN<5>";
98"P5E_CPU1_P0_RX_DN<15>";
99"P5E_CPU1_P0_RX_DN<14>";
100"P5E_CPU1_P0_RX_DP<12>";
101"P5E_CPU1_P0_RX_DP<11>";
102"P5E_CPU1_P0_RX_DP<5>";
103"P5E_CPU1_P1_RX_DP<13>";
104"P5E_CPU1_P1_RX_DP<12>";
105"P5E_CPU1_P1_RX_DP<10>";
106"P5E_CPU1_P0_RX_DN<13>";
107"P5E_CPU1_P1_TX_DP<15>";
108"P5E_CPU1_P1_TX_DP<14>";
109"P5E_CPU1_P1_TX_DP<13>";
110"P5E_CPU1_P1_TX_DP<12>";
111"P5E_CPU1_P1_TX_DP<11>";
112"P5E_CPU1_P1_TX_DP<10>";
113"P5E_CPU1_P1_TX_DP<9>";
114"P5E_CPU1_P1_TX_DN<15>";
115"P5E_CPU1_P1_TX_DN<14>";
116"P5E_CPU1_P1_TX_DN<13>";
117"P5E_CPU1_P1_TX_DN<12>";
118"P5E_CPU1_P1_TX_DN<11>";
119"P5E_CPU1_P1_TX_DN<10>";
120"P5E_CPU1_P1_TX_DN<9>";
121"P5E_CPU1_P1_TX_DP<7>";
122"P5E_CPU1_P1_TX_DP<6>";
123"P5E_CPU1_P1_TX_DP<5>";
124"P5E_CPU1_P1_TX_DP<4>";
125"P5E_CPU1_P1_TX_DP<8>";
126"P5E_CPU1_P1_TX_DP<3>";
127"P5E_CPU1_P1_TX_DP<2>";
128"P5E_CPU1_P1_TX_DP<1>";
129"P5E_CPU1_P1_TX_DN<7>";
130"P5E_CPU1_P1_TX_DN<6>";
131"P5E_CPU1_P1_TX_DN<5>";
132"P5E_CPU1_P1_TX_DN<4>";
133"P5E_CPU1_P1_TX_DN<3>";
134"P5E_CPU1_P1_TX_DN<2>";
135"P5E_CPU1_P1_TX_DN<0>";
136"P5E_CPU1_P1_TX_DN<8>";
%"GENOA_SP5"
"15","(-4700,4750)","0","pure_quanta","I147";
;
LOCATION"U26"
$SEC"15"
CDS_SEC"15"
MATERIAL"IO"
VALUE"SOCKET6096_13568-001"
PART_TYPE"SMLF"
CDS_LMAN_SYM_OUTLINE"-1100,950,1100,-950"
NEEDS_NO_SIZE"TRUE"
CDS_LIB"pure_quanta"
PART_NUMBER"DGA^6000030";
"P0_RXP11||SATA13_RXP"
$PN"BU43"101;
"P0_TXP12||SATA14_TXP"
$PN"CN44"66;
"P0_TXP15||SATA17_TXP"
$PN"CM41"46;
"P0_RXN11||SATA13_RXN"
$PN"BU44"52;
"P0_RXN14||SATA16_RXN"
$PN"BV41"99;
"P0_TXN15||SATA17_TXN"
$PN"CM40"84;
"P0_RXP13||SATA15_RXP"
$PN"CB40"51;
"P0_TXN9||SATA11_TXN"
$PN"CN46"40;
"P0_TXN12||SATA14_TXN"
$PN"CN43"62;
"P0_RXP10||SATA12_RXP"
$PN"CA43"48;
"P0_RXN9||SATA11_RXN"
$PN"BW44"55;
"P0_TXP11||SATA13_TXP"
$PN"CU44"72;
"P0_TXP14||SATA16_TXP"
$PN"CP41"64;
"P0_RXN10||SATA12_RXN"
$PN"CA44"54;
"P0_RXN13||SATA15_RXN"
$PN"CB41"106;
"P0_TXP9||SATA11_TXP"
$PN"CN47"41;
"P0_RXP9||SATA11_RXP"
$PN"BW43"56;
"P0_TXN14||SATA16_TXN"
$PN"CP40"85;
"P0_RXP12||SATA14_RXP"
$PN"BY40"100;
"P0_RXP15||SATA17_RXP"
$PN"BT40"49;
"P0_TXN8||SATA10_TXN"
$PN"CU46"42;
"P0_TXN11||SATA13_TXN"
$PN"CU43"63;
"P0_RXN8||SATA10_RXN"
$PN"BU47"57;
"P0_TXP13||SATA15_TXP"
$PN"CT41"65;
"P0_TXP10||SATA12_TXP"
$PN"CR44"95;
"P0_RXN15||SATA17_RXN"
$PN"BT41"98;
"P0_TXP8||SATA10_TXP"
$PN"CU47"67;
"P0_RXN12||SATA14_RXN"
$PN"BY41"53;
"P0_RXP8||SATA10_RXP"
$PN"BU46"60;
"P0_RXP14||SATA16_RXP"
$PN"BV40"50;
"P0_TXN10||SATA12_TXN"
$PN"CR43"73;
"P0_TXN13||SATA15_TXN"
$PN"CT40"61;
"P0_TXP3||SATA03_TXP"
$PN"CN50"79;
"P0_TXP6||SATA06_TXP"
$PN"CL50"96;
"P0_TXP0||SATA00_TXP"
$PN"CN53"87;
"P0_RXP3||SATA03_RXP"
$PN"BW49"91;
"P0_RXP6||SATA06_RXP"
$PN"BW46"70;
"P0_TXN5||SATA05_TXN"
$PN"CU49"97;
"P0_RXP0||SATA00_RXP"
$PN"BW52"47;
"P0_TXN2||SATA02_TXN"
$PN"CL52"80;
"P0_RXN2||SATA02_RXN"
$PN"BU53"90;
"P0_RXN5||SATA05_RXN"
$PN"BU50"69;
"P0_TXP2||SATA02_TXP"
$PN"CL53"81;
"P0_TXP5||SATA05_TXP"
$PN"CU50"94;
"P0_RXP5||SATA05_RXP"
$PN"BU49"102;
"P0_RXP2||SATA02_RXP"
$PN"BU52"89;
"P0_TXN1||SATA01_TXN"
$PN"CR52"82;
"P0_TXN7||SATA07_TXN"
$PN"CR46"68;
"P0_TXN4||SATA04_TXN"
$PN"CR49"76;
"P0_RXN7||SATA07_RXN"
$PN"CA47"43;
"P0_RXN1||SATA01_RXN"
$PN"CA53"44;
"P0_RXN4||SATA04_RXN"
$PN"CA50"71;
"P0_TXP7||SATA07_TXP"
$PN"CR47"74;
"P0_TXP1||SATA01_TXP"
$PN"CR53"83;
"P0_TXP4||SATA04_TXP"
$PN"CR50"77;
"P0_RXP4||SATA04_RXP"
$PN"CA49"93;
"P0_RXP7||SATA07_RXP"
$PN"CA46"59;
"P0_TXN6||SATA06_TXN"
$PN"CL49"75;
"P0_RXP1||SATA01_RXP"
$PN"CA52"88;
"P0_TXN0||SATA00_TXN"
$PN"CN52"86;
"P0_TXN3||SATA03_TXN"
$PN"CN49"78;
"P0_RXN3||SATA03_RXN"
$PN"BW50"92;
"P0_RXN6||SATA06_RXN"
$PN"BW47"58;
"P0_RXN0||SATA00_RXN"
$PN"BW53"45;
%"GENOA_SP5"
"16","(-4700,2100)","0","pure_quanta","I148";
;
LOCATION"U26"
$SEC"16"
CDS_SEC"16"
PART_TYPE"SMLF"
MATERIAL"IO"
VALUE"SOCKET6096_13568-001"
CDS_LIB"pure_quanta"
CDS_LMAN_SYM_OUTLINE"-1100,950,1100,-950"
NEEDS_NO_SIZE"TRUE"
PART_NUMBER"DGA^6000030";
"P1_RXN6"
$PN"CE47"19;
"P1_RXN5"
$PN"CC50"20;
"P1_RXP7"
$PN"CG46"31;
"P1_TXN7"
$PN"DA46"129;
"P1_RXN4"
$PN"CG50"21;
"P1_RXP6"
$PN"CE46"32;
"P1_TXN6"
$PN"CW49"130;
"P1_RXN3"
$PN"CE50"22;
"P1_RXP5"
$PN"CC49"33;
"P1_TXN5"
$PN"DC49"131;
"P1_TXP7"
$PN"DA47"121;
"P1_RXN2"
$PN"CC53"9;
"P1_RXP4"
$PN"CG49"34;
"P1_TXN4"
$PN"DA49"132;
"P1_TXP6"
$PN"CW50"122;
"P1_RXN1"
$PN"CG53"23;
"P1_RXP3"
$PN"CE49"35;
"P1_TXN3"
$PN"CW52"133;
"P1_TXP5"
$PN"DC50"123;
"P1_RXN0"
$PN"CE53"11;
"P1_RXP2"
$PN"CC52"36;
"P1_TXN2"
$PN"DC52"134;
"P1_TXP4"
$PN"DA50"124;
"P1_RXP1"
$PN"CG52"38;
"P1_TXN1"
$PN"DA52"39;
"P1_TXP3"
$PN"CW53"126;
"P1_RXP0"
$PN"CE52"37;
"P1_TXN0"
$PN"CU52"135;
"P1_TXP2"
$PN"DC53"127;
"P1_TXP1"
$PN"DA53"128;
"P1_TXP0"
$PN"CU53"10;
"P1_RXN7"
$PN"CG47"18;
"P1_TXN15"
$PN"CV40"114;
"P1_TXP15"
$PN"CV41"107;
"P1_TXN14"
$PN"CY40"115;
"P1_TXP14"
$PN"CY41"108;
"P1_TXN13"
$PN"DB40"116;
"P1_TXP13"
$PN"DB41"109;
"P1_TXN12"
$PN"CW43"117;
"P1_TXP12"
$PN"CW44"110;
"P1_TXN11"
$PN"DC43"118;
"P1_TXP11"
$PN"DC44"111;
"P1_TXN10"
$PN"DA43"119;
"P1_TXP10"
$PN"DA44"112;
"P1_TXN9"
$PN"CW46"120;
"P1_TXP9"
$PN"CW47"113;
"P1_TXN8"
$PN"DC46"136;
"P1_TXP8"
$PN"DC47"125;
"P1_RXN15"
$PN"CD41"25;
"P1_RXP15"
$PN"CD40"26;
"P1_RXN14"
$PN"CF41"24;
"P1_RXP14"
$PN"CF40"27;
"P1_RXN13"
$PN"CH41"12;
"P1_RXP13"
$PN"CH40"103;
"P1_RXN12"
$PN"CC44"13;
"P1_RXP12"
$PN"CC43"104;
"P1_RXN11"
$PN"CJ44"14;
"P1_RXP11"
$PN"CJ43"28;
"P1_RXN10"
$PN"CG44"15;
"P1_RXP10"
$PN"CG43"105;
"P1_RXN9"
$PN"CE44"16;
"P1_RXP9"
$PN"CE43"29;
"P1_RXN8"
$PN"CC47"17;
"P1_RXP8"
$PN"CC46"30;
%"TAP"
"6","(-2875,2850)","2","mstr_standard","I186";
;
ROOM"RISER1"
BOM_COST"IO_SLOT"
CDS_LIB"mstr_standard"
BODY_TYPE"PLUMBING"
HDL_TAP"TRUE";
"B \NAC \NWC"1;
"S \NAC"
BN"0"135;
%"TAP"
"6","(-2875,2750)","2","mstr_standard","I187";
;
ROOM"RISER1"
CDS_LIB"mstr_standard"
BOM_COST"IO_SLOT"
BODY_TYPE"PLUMBING"
HDL_TAP"TRUE";
"B \NAC \NWC"1;
"S \NAC"
BN"1"39;
%"TAP"
"6","(-2875,2650)","2","standard","I188";
;
ROOM"RISER1"
CDS_LIB"standard"
BOM_COST"IO_SLOT"
BODY_TYPE"PLUMBING"
HDL_TAP"TRUE";
"B \NAC \NWC"1;
"S \NAC"
BN"2"134;
%"TAP"
"6","(-2875,2450)","2","standard","I189";
;
ROOM"RISER1"
CDS_LIB"standard"
BOM_COST"IO_SLOT"
BODY_TYPE"PLUMBING"
HDL_TAP"TRUE";
"B \NAC \NWC"1;
"S \NAC"
BN"4"132;
%"TAP"
"6","(-2875,2550)","2","standard","I190";
;
ROOM"RISER1"
CDS_LIB"standard"
BOM_COST"IO_SLOT"
BODY_TYPE"PLUMBING"
HDL_TAP"TRUE";
"B \NAC \NWC"1;
"S \NAC"
BN"3"133;
%"TAP"
"6","(-2875,2350)","2","standard","I191";
;
ROOM"RISER1"
CDS_LIB"standard"
BOM_COST"IO_SLOT"
BODY_TYPE"PLUMBING"
HDL_TAP"TRUE";
"B \NAC \NWC"1;
"S \NAC"
BN"5"131;
%"TAP"
"6","(-2875,2250)","2","standard","I192";
;
ROOM"RISER1"
CDS_LIB"standard"
BOM_COST"IO_SLOT"
BODY_TYPE"PLUMBING"
HDL_TAP"TRUE";
"B \NAC \NWC"1;
"S \NAC"
BN"6"130;
%"TAP"
"6","(-2875,2050)","2","standard","I193";
;
ROOM"RISER1"
CDS_LIB"standard"
BOM_COST"IO_SLOT"
BODY_TYPE"PLUMBING"
HDL_TAP"TRUE";
"B \NAC \NWC"1;
"S \NAC"
BN"8"136;
%"TAP"
"6","(-2875,2150)","2","standard","I194";
;
ROOM"RISER1"
CDS_LIB"standard"
BOM_COST"IO_SLOT"
BODY_TYPE"PLUMBING"
HDL_TAP"TRUE";
"B \NAC \NWC"1;
"S \NAC"
BN"7"129;
%"TAP"
"6","(-3025,2900)","2","mstr_standard","I196";
;
ROOM"RISER1"
CDS_LIB"mstr_standard"
BOM_COST"IO_SLOT"
BODY_TYPE"PLUMBING"
HDL_TAP"TRUE";
"B \NAC \NWC"2;
"S \NAC"
BN"0"10;
%"TAP"
"6","(-3025,2700)","2","standard","I197";
;
ROOM"RISER1"
CDS_LIB"standard"
BOM_COST"IO_SLOT"
BODY_TYPE"PLUMBING"
HDL_TAP"TRUE";
"B \NAC \NWC"2;
"S \NAC"
BN"2"127;
%"TAP"
"6","(-3025,2800)","2","mstr_standard","I198";
;
ROOM"RISER1"
CDS_LIB"mstr_standard"
BOM_COST"IO_SLOT"
BODY_TYPE"PLUMBING"
HDL_TAP"TRUE";
"B \NAC \NWC"2;
"S \NAC"
BN"1"128;
%"TAP"
"6","(-3025,2600)","2","standard","I199";
;
ROOM"RISER1"
CDS_LIB"standard"
BOM_COST"IO_SLOT"
BODY_TYPE"PLUMBING"
HDL_TAP"TRUE";
"B \NAC \NWC"2;
"S \NAC"
BN"3"126;
%"TAP"
"6","(-3025,2500)","2","standard","I200";
;
ROOM"RISER1"
CDS_LIB"standard"
BOM_COST"IO_SLOT"
BODY_TYPE"PLUMBING"
HDL_TAP"TRUE";
"B \NAC \NWC"2;
"S \NAC"
BN"4"124;
%"TAP"
"6","(-3025,2400)","2","standard","I201";
;
ROOM"RISER1"
CDS_LIB"standard"
BOM_COST"IO_SLOT"
BODY_TYPE"PLUMBING"
HDL_TAP"TRUE";
"B \NAC \NWC"2;
"S \NAC"
BN"5"123;
%"TAP"
"6","(-3025,2300)","2","standard","I202";
;
ROOM"RISER1"
CDS_LIB"standard"
BOM_COST"IO_SLOT"
BODY_TYPE"PLUMBING"
HDL_TAP"TRUE";
"B \NAC \NWC"2;
"S \NAC"
BN"6"122;
%"TAP"
"6","(-3025,2200)","2","standard","I203";
;
ROOM"RISER1"
CDS_LIB"standard"
BOM_COST"IO_SLOT"
BODY_TYPE"PLUMBING"
HDL_TAP"TRUE";
"B \NAC \NWC"2;
"S \NAC"
BN"7"121;
%"TAP"
"6","(-3025,2100)","2","standard","I204";
;
ROOM"RISER1"
CDS_LIB"standard"
BOM_COST"IO_SLOT"
BODY_TYPE"PLUMBING"
HDL_TAP"TRUE";
"B \NAC \NWC"2;
"S \NAC"
BN"8"125;
%"TAP"
"6","(-2875,1950)","2","standard","I205";
;
ROOM"RISER1"
CDS_LIB"standard"
BOM_COST"IO_SLOT"
BODY_TYPE"PLUMBING"
HDL_TAP"TRUE";
"B \NAC \NWC"1;
"S \NAC"
BN"9"120;
%"TAP"
"6","(-2875,1850)","2","standard","I206";
;
ROOM"RISER1"
CDS_LIB"standard"
BOM_COST"IO_SLOT"
BODY_TYPE"PLUMBING"
HDL_TAP"TRUE";
"B \NAC \NWC"1;
"S \NAC"
BN"10"119;
%"TAP"
"6","(-2875,1750)","2","standard","I207";
;
ROOM"RISER1"
CDS_LIB"standard"
BOM_COST"IO_SLOT"
BODY_TYPE"PLUMBING"
HDL_TAP"TRUE";
"B \NAC \NWC"1;
"S \NAC"
BN"11"118;
%"TAP"
"6","(-2875,1550)","2","standard","I208";
;
ROOM"RISER1"
CDS_LIB"standard"
BOM_COST"IO_SLOT"
BODY_TYPE"PLUMBING"
HDL_TAP"TRUE";
"B \NAC \NWC"1;
"S \NAC"
BN"13"116;
%"TAP"
"6","(-2875,1650)","2","standard","I209";
;
ROOM"RISER1"
CDS_LIB"standard"
BOM_COST"IO_SLOT"
BODY_TYPE"PLUMBING"
HDL_TAP"TRUE";
"B \NAC \NWC"1;
"S \NAC"
BN"12"117;
%"TAP"
"6","(-2875,1450)","2","standard","I210";
;
ROOM"RISER1"
BOM_COST"IO_SLOT"
CDS_LIB"standard"
BODY_TYPE"PLUMBING"
HDL_TAP"TRUE";
"B \NAC \NWC"1;
"S \NAC"
BN"14"115;
%"TAP"
"6","(-2875,1350)","2","standard","I211";
;
ROOM"RISER1"
CDS_LIB"standard"
BOM_COST"IO_SLOT"
BODY_TYPE"PLUMBING"
HDL_TAP"TRUE";
"B \NAC \NWC"1;
"S \NAC"
BN"15"114;
%"TAP"
"6","(-3025,2000)","2","standard","I212";
;
ROOM"RISER1"
CDS_LIB"standard"
BOM_COST"IO_SLOT"
BODY_TYPE"PLUMBING"
HDL_TAP"TRUE";
"B \NAC \NWC"2;
"S \NAC"
BN"9"113;
%"TAP"
"6","(-3025,1900)","2","standard","I213";
;
ROOM"RISER1"
CDS_LIB"standard"
BOM_COST"IO_SLOT"
BODY_TYPE"PLUMBING"
HDL_TAP"TRUE";
"B \NAC \NWC"2;
"S \NAC"
BN"10"112;
%"TAP"
"6","(-3025,1800)","2","standard","I214";
;
ROOM"RISER1"
CDS_LIB"standard"
BOM_COST"IO_SLOT"
BODY_TYPE"PLUMBING"
HDL_TAP"TRUE";
"B \NAC \NWC"2;
"S \NAC"
BN"11"111;
%"TAP"
"6","(-3025,1700)","2","standard","I215";
;
ROOM"RISER1"
CDS_LIB"standard"
BOM_COST"IO_SLOT"
BODY_TYPE"PLUMBING"
HDL_TAP"TRUE";
"B \NAC \NWC"2;
"S \NAC"
BN"12"110;
%"TAP"
"6","(-3025,1600)","2","standard","I216";
;
ROOM"RISER1"
CDS_LIB"standard"
BOM_COST"IO_SLOT"
BODY_TYPE"PLUMBING"
HDL_TAP"TRUE";
"B \NAC \NWC"2;
"S \NAC"
BN"13"109;
%"TAP"
"6","(-3025,1500)","2","standard","I217";
;
ROOM"RISER1"
CDS_LIB"standard"
BOM_COST"IO_SLOT"
BODY_TYPE"PLUMBING"
HDL_TAP"TRUE";
"B \NAC \NWC"2;
"S \NAC"
BN"14"108;
%"TAP"
"6","(-3025,1400)","2","standard","I218";
;
ROOM"RISER1"
CDS_LIB"standard"
BOM_COST"IO_SLOT"
BODY_TYPE"PLUMBING"
HDL_TAP"TRUE";
"B \NAC \NWC"2;
"S \NAC"
BN"15"107;
%"TAP"
"6","(-6450,5550)","0","mstr_standard","I219";
;
CDS_LIB"mstr_standard"
BODY_TYPE"PLUMBING"
HDL_TAP"TRUE";
"B \NAC \NWC"5;
"S \NAC"
BN"0"47;
%"TAP"
"6","(-6450,5350)","0","mstr_standard","I220";
;
CDS_LIB"mstr_standard"
BODY_TYPE"PLUMBING"
HDL_TAP"TRUE";
"B \NAC \NWC"5;
"S \NAC"
BN"2"89;
%"TAP"
"6","(-6450,5450)","0","mstr_standard","I221";
;
CDS_LIB"mstr_standard"
BODY_TYPE"PLUMBING"
HDL_TAP"TRUE";
"B \NAC \NWC"5;
"S \NAC"
BN"1"88;
%"TAP"
"6","(-6450,5250)","0","standard","I222";
;
CDS_LIB"standard"
BODY_TYPE"PLUMBING"
HDL_TAP"TRUE";
"B \NAC \NWC"5;
"S \NAC"
BN"3"91;
%"TAP"
"6","(-6450,5150)","0","standard","I223";
;
CDS_LIB"standard"
BODY_TYPE"PLUMBING"
HDL_TAP"TRUE";
"B \NAC \NWC"5;
"S \NAC"
BN"4"93;
%"TAP"
"6","(-6450,5050)","0","standard","I228";
;
CDS_LIB"standard"
BODY_TYPE"PLUMBING"
HDL_TAP"TRUE";
"B \NAC \NWC"5;
"S \NAC"
BN"5"102;
%"TAP"
"6","(-6450,4850)","0","standard","I229";
;
CDS_LIB"standard"
BODY_TYPE"PLUMBING"
HDL_TAP"TRUE";
"B \NAC \NWC"5;
"S \NAC"
BN"7"59;
%"TAP"
"6","(-6450,4950)","0","standard","I230";
;
CDS_LIB"standard"
BODY_TYPE"PLUMBING"
HDL_TAP"TRUE";
"B \NAC \NWC"5;
"S \NAC"
BN"6"70;
%"TAP"
"6","(-6450,4750)","0","standard","I231";
;
CDS_LIB"standard"
BODY_TYPE"PLUMBING"
HDL_TAP"TRUE";
"B \NAC \NWC"5;
"S \NAC"
BN"8"60;
%"TAP"
"6","(-6450,4650)","0","standard","I232";
;
CDS_LIB"standard"
BODY_TYPE"PLUMBING"
HDL_TAP"TRUE";
"B \NAC \NWC"5;
"S \NAC"
BN"9"56;
%"TAP"
"6","(-6450,4450)","0","standard","I238";
;
CDS_LIB"standard"
BODY_TYPE"PLUMBING"
HDL_TAP"TRUE";
"B \NAC \NWC"5;
"S \NAC"
BN"11"101;
%"TAP"
"6","(-6450,4550)","0","standard","I239";
;
CDS_LIB"standard"
BODY_TYPE"PLUMBING"
HDL_TAP"TRUE";
"B \NAC \NWC"5;
"S \NAC"
BN"10"48;
%"TAP"
"6","(-6450,4350)","0","standard","I240";
;
CDS_LIB"standard"
BODY_TYPE"PLUMBING"
HDL_TAP"TRUE";
"B \NAC \NWC"5;
"S \NAC"
BN"12"100;
%"TAP"
"6","(-6450,4250)","0","standard","I241";
;
CDS_LIB"standard"
BODY_TYPE"PLUMBING"
HDL_TAP"TRUE";
"B \NAC \NWC"5;
"S \NAC"
BN"13"51;
%"TAP"
"6","(-6450,4150)","0","standard","I242";
;
CDS_LIB"standard"
BODY_TYPE"PLUMBING"
HDL_TAP"TRUE";
"B \NAC \NWC"5;
"S \NAC"
BN"14"50;
%"TAP"
"6","(-6450,4050)","0","standard","I253";
;
CDS_LIB"standard"
BODY_TYPE"PLUMBING"
HDL_TAP"TRUE";
"B \NAC \NWC"5;
"S \NAC"
BN"15"49;
%"TAP"
"6","(-6450,2600)","0","standard","I255";
;
CDS_LIB"standard"
BODY_TYPE"PLUMBING"
HDL_TAP"TRUE";
"B \NAC \NWC"4;
"S \NAC"
BN"3"35;
%"TAP"
"6","(-6450,2700)","0","mstr_standard","I256";
;
CDS_LIB"mstr_standard"
BODY_TYPE"PLUMBING"
HDL_TAP"TRUE";
"B \NAC \NWC"4;
"S \NAC"
BN"2"36;
%"TAP"
"6","(-6450,2900)","0","mstr_standard","I257";
;
CDS_LIB"mstr_standard"
BODY_TYPE"PLUMBING"
HDL_TAP"TRUE";
"B \NAC \NWC"4;
"S \NAC"
BN"0"37;
%"TAP"
"6","(-6450,2800)","0","mstr_standard","I258";
;
CDS_LIB"mstr_standard"
BODY_TYPE"PLUMBING"
HDL_TAP"TRUE";
"B \NAC \NWC"4;
"S \NAC"
BN"1"38;
%"TAP"
"6","(-6600,2850)","0","mstr_standard","I259";
;
CDS_LIB"mstr_standard"
BODY_TYPE"PLUMBING"
HDL_TAP"TRUE";
"B \NAC \NWC"8;
"S \NAC"
BN"0"11;
%"TAP"
"6","(-6600,2750)","0","mstr_standard","I260";
;
CDS_LIB"mstr_standard"
BODY_TYPE"PLUMBING"
HDL_TAP"TRUE";
"B \NAC \NWC"8;
"S \NAC"
BN"1"23;
%"TAP"
"6","(-6600,2650)","0","standard","I261";
;
CDS_LIB"standard"
BODY_TYPE"PLUMBING"
HDL_TAP"TRUE";
"B \NAC \NWC"8;
"S \NAC"
BN"2"9;
%"TAP"
"6","(-6450,2100)","0","standard","I262";
;
CDS_LIB"standard"
BODY_TYPE"PLUMBING"
HDL_TAP"TRUE";
"B \NAC \NWC"4;
"S \NAC"
BN"8"30;
%"TAP"
"6","(-6450,2200)","0","standard","I263";
;
CDS_LIB"standard"
BODY_TYPE"PLUMBING"
HDL_TAP"TRUE";
"B \NAC \NWC"4;
"S \NAC"
BN"7"31;
%"TAP"
"6","(-6450,2300)","0","standard","I264";
;
CDS_LIB"standard"
BODY_TYPE"PLUMBING"
HDL_TAP"TRUE";
"B \NAC \NWC"4;
"S \NAC"
BN"6"32;
%"TAP"
"6","(-6450,2500)","0","standard","I265";
;
CDS_LIB"standard"
BODY_TYPE"PLUMBING"
HDL_TAP"TRUE";
"B \NAC \NWC"4;
"S \NAC"
BN"4"34;
%"TAP"
"6","(-6450,2400)","0","standard","I266";
;
CDS_LIB"standard"
BODY_TYPE"PLUMBING"
HDL_TAP"TRUE";
"B \NAC \NWC"4;
"S \NAC"
BN"5"33;
%"TAP"
"6","(-6600,2550)","0","standard","I267";
;
CDS_LIB"standard"
BODY_TYPE"PLUMBING"
HDL_TAP"TRUE";
"B \NAC \NWC"8;
"S \NAC"
BN"3"22;
%"TAP"
"6","(-6600,2450)","0","standard","I268";
;
CDS_LIB"standard"
BODY_TYPE"PLUMBING"
HDL_TAP"TRUE";
"B \NAC \NWC"8;
"S \NAC"
BN"4"21;
%"TAP"
"6","(-6600,2350)","0","standard","I269";
;
CDS_LIB"standard"
BODY_TYPE"PLUMBING"
HDL_TAP"TRUE";
"B \NAC \NWC"8;
"S \NAC"
BN"5"20;
%"TAP"
"6","(-6600,2150)","0","standard","I270";
;
CDS_LIB"standard"
BODY_TYPE"PLUMBING"
HDL_TAP"TRUE";
"B \NAC \NWC"8;
"S \NAC"
BN"7"18;
%"TAP"
"6","(-6600,2250)","0","standard","I271";
;
CDS_LIB"standard"
BODY_TYPE"PLUMBING"
HDL_TAP"TRUE";
"B \NAC \NWC"8;
"S \NAC"
BN"6"19;
%"TAP"
"6","(-6600,2050)","0","standard","I272";
;
CDS_LIB"standard"
BODY_TYPE"PLUMBING"
HDL_TAP"TRUE";
"B \NAC \NWC"8;
"S \NAC"
BN"8"17;
%"TAP"
"6","(-6450,1800)","0","standard","I275";
;
CDS_LIB"standard"
BODY_TYPE"PLUMBING"
HDL_TAP"TRUE";
"B \NAC \NWC"4;
"S \NAC"
BN"11"28;
%"TAP"
"6","(-6450,1900)","0","standard","I276";
;
CDS_LIB"standard"
BODY_TYPE"PLUMBING"
HDL_TAP"TRUE";
"B \NAC \NWC"4;
"S \NAC"
BN"10"105;
%"TAP"
"6","(-6450,2000)","0","standard","I277";
;
CDS_LIB"standard"
BODY_TYPE"PLUMBING"
HDL_TAP"TRUE";
"B \NAC \NWC"4;
"S \NAC"
BN"9"29;
%"TAP"
"6","(-6450,1700)","0","standard","I278";
;
CDS_LIB"standard"
BODY_TYPE"PLUMBING"
HDL_TAP"TRUE";
"B \NAC \NWC"4;
"S \NAC"
BN"12"104;
%"TAP"
"6","(-6450,1600)","0","standard","I279";
;
CDS_LIB"standard"
BODY_TYPE"PLUMBING"
HDL_TAP"TRUE";
"B \NAC \NWC"4;
"S \NAC"
BN"13"103;
%"TAP"
"6","(-6600,1950)","0","standard","I280";
;
CDS_LIB"standard"
BODY_TYPE"PLUMBING"
HDL_TAP"TRUE";
"B \NAC \NWC"8;
"S \NAC"
BN"9"16;
%"TAP"
"6","(-6600,1850)","0","standard","I281";
;
CDS_LIB"standard"
BODY_TYPE"PLUMBING"
HDL_TAP"TRUE";
"B \NAC \NWC"8;
"S \NAC"
BN"10"15;
%"TAP"
"6","(-6600,1750)","0","standard","I282";
;
CDS_LIB"standard"
BODY_TYPE"PLUMBING"
HDL_TAP"TRUE";
"B \NAC \NWC"8;
"S \NAC"
BN"11"14;
%"TAP"
"6","(-6600,1650)","0","standard","I283";
;
CDS_LIB"standard"
BODY_TYPE"PLUMBING"
HDL_TAP"TRUE";
"B \NAC \NWC"8;
"S \NAC"
BN"12"13;
%"TAP"
"6","(-6600,1550)","0","standard","I284";
;
CDS_LIB"standard"
BODY_TYPE"PLUMBING"
HDL_TAP"TRUE";
"B \NAC \NWC"8;
"S \NAC"
BN"13"12;
%"TAP"
"6","(-6450,1500)","0","standard","I285";
;
CDS_LIB"standard"
BODY_TYPE"PLUMBING"
HDL_TAP"TRUE";
"B \NAC \NWC"4;
"S \NAC"
BN"14"27;
%"TAP"
"6","(-6450,1400)","0","standard","I286";
;
CDS_LIB"standard"
BODY_TYPE"PLUMBING"
HDL_TAP"TRUE";
"B \NAC \NWC"4;
"S \NAC"
BN"15"26;
%"TAP"
"6","(-6600,1350)","0","standard","I287";
;
CDS_LIB"standard"
BODY_TYPE"PLUMBING"
HDL_TAP"TRUE";
"B \NAC \NWC"8;
"S \NAC"
BN"15"25;
%"TAP"
"6","(-6600,1450)","0","standard","I288";
;
CDS_LIB"standard"
BODY_TYPE"PLUMBING"
HDL_TAP"TRUE";
"B \NAC \NWC"8;
"S \NAC"
BN"14"24;
%"TAP"
"6","(-2950,5550)","2","mstr_standard","I291";
;
ROOM"RISER1"
BOM_COST"IO_SLOT"
CDS_LIB"mstr_standard"
BODY_TYPE"PLUMBING"
HDL_TAP"TRUE";
"B \NAC \NWC"7;
"S \NAC"
BN"0"87;
%"TAP"
"6","(-2950,5350)","2","standard","I295";
;
ROOM"RISER1"
BOM_COST"IO_SLOT"
CDS_LIB"standard"
BODY_TYPE"PLUMBING"
HDL_TAP"TRUE";
"B \NAC \NWC"7;
"S \NAC"
BN"2"81;
%"TAP"
"6","(-2950,5450)","2","mstr_standard","I296";
;
ROOM"RISER1"
BOM_COST"IO_SLOT"
CDS_LIB"mstr_standard"
BODY_TYPE"PLUMBING"
HDL_TAP"TRUE";
"B \NAC \NWC"7;
"S \NAC"
BN"1"83;
%"TAP"
"6","(-2950,5150)","2","standard","I299";
;
ROOM"RISER1"
BOM_COST"IO_SLOT"
CDS_LIB"standard"
BODY_TYPE"PLUMBING"
HDL_TAP"TRUE";
"B \NAC \NWC"7;
"S \NAC"
BN"4"77;
%"TAP"
"6","(-2950,5250)","2","standard","I300";
;
ROOM"RISER1"
BOM_COST"IO_SLOT"
CDS_LIB"standard"
BODY_TYPE"PLUMBING"
HDL_TAP"TRUE";
"B \NAC \NWC"7;
"S \NAC"
BN"3"79;
%"TAP"
"6","(-2950,5050)","2","standard","I301";
;
ROOM"RISER1"
BOM_COST"IO_SLOT"
CDS_LIB"standard"
BODY_TYPE"PLUMBING"
HDL_TAP"TRUE";
"B \NAC \NWC"7;
"S \NAC"
BN"5"94;
%"TAP"
"6","(-2950,4950)","2","standard","I305";
;
ROOM"RISER1"
BOM_COST"IO_SLOT"
CDS_LIB"standard"
BODY_TYPE"PLUMBING"
HDL_TAP"TRUE";
"B \NAC \NWC"7;
"S \NAC"
BN"6"96;
%"TAP"
"6","(-2950,4850)","2","standard","I306";
;
ROOM"RISER1"
BOM_COST"IO_SLOT"
CDS_LIB"standard"
BODY_TYPE"PLUMBING"
HDL_TAP"TRUE";
"B \NAC \NWC"7;
"S \NAC"
BN"7"74;
%"TAP"
"6","(-2950,4750)","2","standard","I307";
;
ROOM"RISER1"
BOM_COST"IO_SLOT"
CDS_LIB"standard"
BODY_TYPE"PLUMBING"
HDL_TAP"TRUE";
"B \NAC \NWC"7;
"S \NAC"
BN"8"67;
%"TAP"
"6","(-2950,4650)","2","standard","I311";
;
ROOM"RISER1"
BOM_COST"IO_SLOT"
CDS_LIB"standard"
BODY_TYPE"PLUMBING"
HDL_TAP"TRUE";
"B \NAC \NWC"7;
"S \NAC"
BN"9"41;
%"TAP"
"6","(-2950,4550)","2","standard","I312";
;
ROOM"RISER1"
BOM_COST"IO_SLOT"
CDS_LIB"standard"
BODY_TYPE"PLUMBING"
HDL_TAP"TRUE";
"B \NAC \NWC"7;
"S \NAC"
BN"10"95;
%"TAP"
"6","(-2950,4450)","2","standard","I315";
;
ROOM"RISER1"
BOM_COST"IO_SLOT"
CDS_LIB"standard"
BODY_TYPE"PLUMBING"
HDL_TAP"TRUE";
"B \NAC \NWC"7;
"S \NAC"
BN"11"72;
%"TAP"
"6","(-2950,4350)","2","standard","I316";
;
ROOM"RISER1"
BOM_COST"IO_SLOT"
CDS_LIB"standard"
BODY_TYPE"PLUMBING"
HDL_TAP"TRUE";
"B \NAC \NWC"7;
"S \NAC"
BN"12"66;
%"TAP"
"6","(-2950,4250)","2","standard","I317";
;
ROOM"RISER1"
BOM_COST"IO_SLOT"
CDS_LIB"standard"
BODY_TYPE"PLUMBING"
HDL_TAP"TRUE";
"B \NAC \NWC"7;
"S \NAC"
BN"13"65;
%"TAP"
"6","(-2950,4150)","2","standard","I321";
;
ROOM"RISER1"
BOM_COST"IO_SLOT"
CDS_LIB"standard"
BODY_TYPE"PLUMBING"
HDL_TAP"TRUE";
"B \NAC \NWC"7;
"S \NAC"
BN"14"64;
%"TAP"
"6","(-2950,4050)","2","standard","I322";
;
ROOM"RISER1"
BOM_COST"IO_SLOT"
CDS_LIB"standard"
BODY_TYPE"PLUMBING"
HDL_TAP"TRUE";
"B \NAC \NWC"7;
"S \NAC"
BN"15"46;
%"TAP"
"6","(-6600,5500)","0","mstr_standard","I323";
;
CDS_LIB"mstr_standard"
BODY_TYPE"PLUMBING"
HDL_TAP"TRUE";
"B \NAC \NWC"3;
"S \NAC"
BN"0"45;
%"TAP"
"6","(-6600,5400)","0","mstr_standard","I324";
;
CDS_LIB"mstr_standard"
BODY_TYPE"PLUMBING"
HDL_TAP"TRUE";
"B \NAC \NWC"3;
"S \NAC"
BN"1"44;
%"TAP"
"6","(-6600,5300)","0","standard","I325";
;
CDS_LIB"standard"
BODY_TYPE"PLUMBING"
HDL_TAP"TRUE";
"B \NAC \NWC"3;
"S \NAC"
BN"2"90;
%"TAP"
"6","(-6600,5200)","0","standard","I326";
;
CDS_LIB"standard"
BODY_TYPE"PLUMBING"
HDL_TAP"TRUE";
"B \NAC \NWC"3;
"S \NAC"
BN"3"92;
%"TAP"
"6","(-6600,5100)","0","standard","I327";
;
CDS_LIB"standard"
BODY_TYPE"PLUMBING"
HDL_TAP"TRUE";
"B \NAC \NWC"3;
"S \NAC"
BN"4"71;
%"TAP"
"6","(-6600,5000)","0","standard","I328";
;
CDS_LIB"standard"
BODY_TYPE"PLUMBING"
HDL_TAP"TRUE";
"B \NAC \NWC"3;
"S \NAC"
BN"5"69;
%"TAP"
"6","(-6600,4800)","0","standard","I329";
;
CDS_LIB"standard"
BODY_TYPE"PLUMBING"
HDL_TAP"TRUE";
"B \NAC \NWC"3;
"S \NAC"
BN"7"43;
%"TAP"
"6","(-6600,4900)","0","standard","I330";
;
CDS_LIB"standard"
BODY_TYPE"PLUMBING"
HDL_TAP"TRUE";
"B \NAC \NWC"3;
"S \NAC"
BN"6"58;
%"TAP"
"6","(-6600,4700)","0","standard","I331";
;
CDS_LIB"standard"
BODY_TYPE"PLUMBING"
HDL_TAP"TRUE";
"B \NAC \NWC"3;
"S \NAC"
BN"8"57;
%"TAP"
"6","(-6600,4600)","0","standard","I332";
;
CDS_LIB"standard"
BODY_TYPE"PLUMBING"
HDL_TAP"TRUE";
"B \NAC \NWC"3;
"S \NAC"
BN"9"55;
%"TAP"
"6","(-6600,4400)","0","standard","I333";
;
CDS_LIB"standard"
BODY_TYPE"PLUMBING"
HDL_TAP"TRUE";
"B \NAC \NWC"3;
"S \NAC"
BN"11"52;
%"TAP"
"6","(-6600,4500)","0","standard","I334";
;
CDS_LIB"standard"
BODY_TYPE"PLUMBING"
HDL_TAP"TRUE";
"B \NAC \NWC"3;
"S \NAC"
BN"10"54;
%"TAP"
"6","(-6600,4300)","0","standard","I335";
;
CDS_LIB"standard"
BODY_TYPE"PLUMBING"
HDL_TAP"TRUE";
"B \NAC \NWC"3;
"S \NAC"
BN"12"53;
%"TAP"
"6","(-6600,4200)","0","standard","I336";
;
CDS_LIB"standard"
BODY_TYPE"PLUMBING"
HDL_TAP"TRUE";
"B \NAC \NWC"3;
"S \NAC"
BN"13"106;
%"TAP"
"6","(-6600,4100)","0","standard","I337";
;
CDS_LIB"standard"
BODY_TYPE"PLUMBING"
HDL_TAP"TRUE";
"B \NAC \NWC"3;
"S \NAC"
BN"14"99;
%"TAP"
"6","(-6600,4000)","0","standard","I338";
;
CDS_LIB"standard"
BODY_TYPE"PLUMBING"
HDL_TAP"TRUE";
"B \NAC \NWC"3;
"S \NAC"
BN"15"98;
%"TAP"
"6","(-2800,4400)","2","standard","I340";
;
ROOM"RISER1"
BOM_COST"IO_SLOT"
CDS_LIB"standard"
BODY_TYPE"PLUMBING"
HDL_TAP"TRUE";
"B \NAC \NWC"6;
"S \NAC"
BN"11"63;
%"TAP"
"6","(-2800,5500)","2","mstr_standard","I342";
;
ROOM"RISER1"
CDS_LIB"mstr_standard"
BOM_COST"IO_SLOT"
BODY_TYPE"PLUMBING"
HDL_TAP"TRUE";
"B \NAC \NWC"6;
"S \NAC"
BN"0"86;
%"TAP"
"6","(-2800,5400)","2","mstr_standard","I343";
;
ROOM"RISER1"
BOM_COST"IO_SLOT"
CDS_LIB"mstr_standard"
BODY_TYPE"PLUMBING"
HDL_TAP"TRUE";
"B \NAC \NWC"6;
"S \NAC"
BN"1"82;
%"TAP"
"6","(-2800,5300)","2","standard","I344";
;
ROOM"RISER1"
BOM_COST"IO_SLOT"
CDS_LIB"standard"
BODY_TYPE"PLUMBING"
HDL_TAP"TRUE";
"B \NAC \NWC"6;
"S \NAC"
BN"2"80;
%"TAP"
"6","(-2800,5200)","2","standard","I345";
;
ROOM"RISER1"
BOM_COST"IO_SLOT"
CDS_LIB"standard"
BODY_TYPE"PLUMBING"
HDL_TAP"TRUE";
"B \NAC \NWC"6;
"S \NAC"
BN"3"78;
%"TAP"
"6","(-2800,5100)","2","standard","I346";
;
ROOM"RISER1"
BOM_COST"IO_SLOT"
CDS_LIB"standard"
BODY_TYPE"PLUMBING"
HDL_TAP"TRUE";
"B \NAC \NWC"6;
"S \NAC"
BN"4"76;
%"TAP"
"6","(-2800,5000)","2","standard","I347";
;
ROOM"RISER1"
BOM_COST"IO_SLOT"
CDS_LIB"standard"
BODY_TYPE"PLUMBING"
HDL_TAP"TRUE";
"B \NAC \NWC"6;
"S \NAC"
BN"5"97;
%"TAP"
"6","(-2800,4900)","2","standard","I348";
;
ROOM"RISER1"
BOM_COST"IO_SLOT"
CDS_LIB"standard"
BODY_TYPE"PLUMBING"
HDL_TAP"TRUE";
"B \NAC \NWC"6;
"S \NAC"
BN"6"75;
%"TAP"
"6","(-2800,4700)","2","standard","I349";
;
ROOM"RISER1"
BOM_COST"IO_SLOT"
CDS_LIB"standard"
BODY_TYPE"PLUMBING"
HDL_TAP"TRUE";
"B \NAC \NWC"6;
"S \NAC"
BN"8"42;
%"TAP"
"6","(-2800,4800)","2","standard","I350";
;
ROOM"RISER1"
BOM_COST"IO_SLOT"
CDS_LIB"standard"
BODY_TYPE"PLUMBING"
HDL_TAP"TRUE";
"B \NAC \NWC"6;
"S \NAC"
BN"7"68;
%"TAP"
"6","(-2800,4600)","2","standard","I351";
;
ROOM"RISER1"
BOM_COST"IO_SLOT"
CDS_LIB"standard"
BODY_TYPE"PLUMBING"
HDL_TAP"TRUE";
"B \NAC \NWC"6;
"S \NAC"
BN"9"40;
%"TAP"
"6","(-2800,4500)","2","standard","I352";
;
ROOM"RISER1"
BOM_COST"IO_SLOT"
CDS_LIB"standard"
BODY_TYPE"PLUMBING"
HDL_TAP"TRUE";
"B \NAC \NWC"6;
"S \NAC"
BN"10"73;
%"TAP"
"6","(-2800,4300)","2","standard","I353";
;
ROOM"RISER1"
BOM_COST"IO_SLOT"
CDS_LIB"standard"
BODY_TYPE"PLUMBING"
HDL_TAP"TRUE";
"B \NAC \NWC"6;
"S \NAC"
BN"12"62;
%"TAP"
"6","(-2800,4200)","2","standard","I354";
;
ROOM"RISER1"
BOM_COST"IO_SLOT"
CDS_LIB"standard"
BODY_TYPE"PLUMBING"
HDL_TAP"TRUE";
"B \NAC \NWC"6;
"S \NAC"
BN"13"61;
%"TAP"
"6","(-2800,4100)","2","standard","I355";
;
ROOM"RISER1"
CDS_LIB"standard"
BOM_COST"IO_SLOT"
BODY_TYPE"PLUMBING"
HDL_TAP"TRUE";
"B \NAC \NWC"6;
"S \NAC"
BN"14"85;
%"TAP"
"6","(-2800,4000)","2","standard","I356";
;
ROOM"RISER1"
BOM_COST"IO_SLOT"
CDS_LIB"standard"
BODY_TYPE"PLUMBING"
HDL_TAP"TRUE";
"B \NAC \NWC"6;
"S \NAC"
BN"15"84;
END.
